# S9S_MB_2U (Grand Teton) — schematic netlist excerpt (pin names and nets, part order shuffled) for the footprints in the layout excerpt that follows; sources: Cadence DE-HDL packaged netlist, KiCad conversion of 03242023_DA0F0TMBIJ0_F0T_Motherboard_J_brd_V01_OCP.brd

R4749  Q_RES  0 5% EMPTY  pkg 0402LF  page 158 : A = OCP_SFF_AUX_PWR_PLD_EN_R ; B = OCP_SFF_AUX_PWR_EN_R2
R4545  Q_RES  4.7K 5% CHIP  pkg 0402LF  page 145 : A = P3V3_AUX ; B = HGX_DETECT

(kicad_pcb
	(version 20260206)
	(generator "pcbnew")
	(generator_version "10.0")
	(general
		(thickness 1.6)
		(legacy_teardrops no)
	)
	(paper "A4")
	(title_block
		(title "03242023_DA0F0TMBIJ0_F0T_Motherboard_J_brd_V01_OCP.brd")
		(comment 1 "Grand Teton / footprints 2573-2574 of 6105")
	)
	(layers
		(0 "F.Cu" signal "TOP")
		(4 "In1.Cu" signal "GND")
		(6 "In2.Cu" signal "IN1")
		(8 "In3.Cu" signal "GND1")
		(10 "In4.Cu" signal "IN2")
		(12 "In5.Cu" signal "GND2")
		(14 "In6.Cu" signal "IN3")
		(16 "In7.Cu" signal "GND3")
		(18 "In8.Cu" signal "VCC")
		(20 "In9.Cu" signal "VCC1")
		(22 "In10.Cu" signal "GND4")
		(24 "In11.Cu" signal "IN4")
		(26 "In12.Cu" signal "GND5")
		(28 "In13.Cu" signal "IN5")
		(30 "In14.Cu" signal "GND6")
		(32 "In15.Cu" signal "IN6")
		(34 "In16.Cu" signal "GND7")
		(2 "B.Cu" signal "BOTTOM")
		(9 "F.Adhes" user "F.Adhesive")
		(11 "B.Adhes" user "B.Adhesive")
		(13 "F.Paste" user "Package Geometry/Pastemask Top")
		(15 "B.Paste" user "Package Geometry/Pastemask Bottom")
		(5 "F.SilkS" user "Ref Des/Silkscreen Top")
		(7 "B.SilkS" user "Ref Des/Silkscreen Bottom")
		(1 "F.Mask" user "Board Geometry/Soldermask Top")
		(3 "B.Mask" user "Board Geometry/Soldermask Bottom")
		(17 "Dwgs.User" user "User.Drawings")
		(19 "Cmts.User" user "User.Comments")
		(21 "Eco1.User" user "User.Eco1")
		(23 "Eco2.User" user "User.Eco2")
		(25 "Edge.Cuts" user "Board Geometry/Outline")
		(27 "Margin" user)
		(31 "F.CrtYd" user "Package Geometry/Place Bound Top")
		(29 "B.CrtYd" user "Package Geometry/Place Bound Bottom")
		(35 "F.Fab" user "Ref Des/Assembly Top")
		(33 "B.Fab" user "Ref Des/Assembly Bottom")
	)
	(footprint ""
		(layer "F.Cu")
		(at 442.76518 -103.3272 90)
		(property "Reference" "R4749"
			(at 0 0 90)
			(layer "F.SilkS")
			(hide yes)
			(effects
				(font
					(size 1.27 1.27)
				)
			)
		)
		(property "Value" ""
			(at 0 0 90)
			(layer "F.Fab")
			(effects
				(font
					(size 1.27 1.27)
				)
			)
		)
		(duplicate_pad_numbers_are_jumpers no)
		(fp_line
			(start 0.7874 -0.4064)
			(end 0.7874 0.4064)
			(stroke
				(width 0.1524)
				(type default)
			)
			(layer "F.SilkS")
		)
		(fp_line
			(start -0.7874 -0.4064)
			(end 0.7874 -0.4064)
			(stroke
				(width 0.1524)
				(type default)
			)
			(layer "F.SilkS")
		)
		(fp_line
			(start 0.7874 0.4064)
			(end -0.7874 0.4064)
			(stroke
				(width 0.1524)
				(type default)
			)
			(layer "F.SilkS")
		)
		(fp_line
			(start -0.7874 0.4064)
			(end -0.7874 -0.4064)
			(stroke
				(width 0.1524)
				(type default)
			)
			(layer "F.SilkS")
		)
		(fp_line
			(start -0.12065 -0.305054)
			(end -0.12065 -0.2794)
			(stroke
				(width 0.1)
				(type default)
			)
			(layer "F.Fab")
		)
		(fp_line
			(start -0.67945 -0.305054)
			(end -0.12065 -0.305054)
			(stroke
				(width 0.1)
				(type default)
			)
			(layer "F.Fab")
		)
		(fp_line
			(start 0.67945 -0.3048)
			(end 0.67945 0.3048)
			(stroke
				(width 0.1)
				(type default)
			)
			(layer "F.Fab")
		)
		(fp_line
			(start 0.12065 -0.3048)
			(end 0.67945 -0.3048)
			(stroke
				(width 0.1)
				(type default)
			)
			(layer "F.Fab")
		)
		(fp_line
			(start 0.12065 -0.2794)
			(end 0.12065 -0.3048)
			(stroke
				(width 0.1)
				(type default)
			)
			(layer "F.Fab")
		)
		(fp_line
			(start -0.12065 -0.2794)
			(end 0.12065 -0.2794)
			(stroke
				(width 0.1)
				(type default)
			)
			(layer "F.Fab")
		)
		(fp_line
			(start 0.120396 0.2794)
			(end -0.12065 0.2794)
			(stroke
				(width 0.1)
				(type default)
			)
			(layer "F.Fab")
		)
		(fp_line
			(start -0.12065 0.2794)
			(end -0.12065 0.3048)
			(stroke
				(width 0.1)
				(type default)
			)
			(layer "F.Fab")
		)
		(fp_line
			(start 0.67945 0.3048)
			(end 0.120396 0.3048)
			(stroke
				(width 0.1)
				(type default)
			)
			(layer "F.Fab")
		)
		(fp_line
			(start 0.120396 0.3048)
			(end 0.120396 0.2794)
			(stroke
				(width 0.1)
				(type default)
			)
			(layer "F.Fab")
		)
		(fp_line
			(start -0.12065 0.3048)
			(end -0.67945 0.3048)
			(stroke
				(width 0.1)
				(type default)
			)
			(layer "F.Fab")
		)
		(fp_line
			(start -0.67945 0.3048)
			(end -0.67945 -0.305054)
			(stroke
				(width 0.1)
				(type default)
			)
			(layer "F.Fab")
		)
		(pad "1" smd circle
			(at -0.40005 0 90)
			(size 0 0)
			(layers "F.Cu" "F.Mask" "F.Paste")
			(net "OCP_SFF_AUX_PWR_PLD_EN_R")
		)
		(pad "2" smd circle
			(at 0.40005 0 90)
			(size 0 0)
			(layers "F.Cu" "F.Mask" "F.Paste")
			(net "OCP_SFF_AUX_PWR_EN_R2")
		)
	)
	(footprint ""
		(layer "F.Cu")
		(at 95.123 -417.683188 -90)
		(property "Reference" "R4545"
			(at 0 0 270)
			(layer "F.SilkS")
			(hide yes)
			(effects
				(font
					(size 1.27 1.27)
				)
			)
		)
		(property "Value" ""
			(at 0 0 270)
			(layer "F.Fab")
			(effects
				(font
					(size 1.27 1.27)
				)
			)
		)
		(duplicate_pad_numbers_are_jumpers no)
		(fp_line
			(start -0.7874 0.4064)
			(end -0.7874 -0.4064)
			(stroke
				(width 0.1524)
				(type default)
			)
			(layer "F.SilkS")
		)
		(fp_line
			(start 0.7874 0.4064)
			(end -0.7874 0.4064)
			(stroke
				(width 0.1524)
				(type default)
			)
			(layer "F.SilkS")
		)
		(fp_line
			(start -0.7874 -0.4064)
			(end 0.7874 -0.4064)
			(stroke
				(width 0.1524)
				(type default)
			)
			(layer "F.SilkS")
		)
		(fp_line
			(start 0.7874 -0.4064)
			(end 0.7874 0.4064)
			(stroke
				(width 0.1524)
				(type default)
			)
			(layer "F.SilkS")
		)
		(fp_line
			(start -0.67945 0.3048)
			(end -0.67945 -0.305054)
			(stroke
				(width 0.1)
				(type default)
			)
			(layer "F.Fab")
		)
		(fp_line
			(start -0.12065 0.3048)
			(end -0.67945 0.3048)
			(stroke
				(width 0.1)
				(type default)
			)
			(layer "F.Fab")
		)
		(fp_line
			(start 0.120396 0.3048)
			(end 0.120396 0.2794)
			(stroke
				(width 0.1)
				(type default)
			)
			(layer "F.Fab")
		)
		(fp_line
			(start 0.67945 0.3048)
			(end 0.120396 0.3048)
			(stroke
				(width 0.1)
				(type default)
			)
			(layer "F.Fab")
		)
		(fp_line
			(start -0.12065 0.2794)
			(end -0.12065 0.3048)
			(stroke
				(width 0.1)
				(type default)
			)
			(layer "F.Fab")
		)
		(fp_line
			(start 0.120396 0.2794)
			(end -0.12065 0.2794)
			(stroke
				(width 0.1)
				(type default)
			)
			(layer "F.Fab")
		)
		(fp_line
			(start -0.12065 -0.2794)
			(end 0.12065 -0.2794)
			(stroke
				(width 0.1)
				(type default)
			)
			(layer "F.Fab")
		)
		(fp_line
			(start 0.12065 -0.2794)
			(end 0.12065 -0.3048)
			(stroke
				(width 0.1)
				(type default)
			)
			(layer "F.Fab")
		)
		(fp_line
			(start 0.12065 -0.3048)
			(end 0.67945 -0.3048)
			(stroke
				(width 0.1)
				(type default)
			)
			(layer "F.Fab")
		)
		(fp_line
			(start 0.67945 -0.3048)
			(end 0.67945 0.3048)
			(stroke
				(width 0.1)
				(type default)
			)
			(layer "F.Fab")
		)
		(fp_line
			(start -0.67945 -0.305054)
			(end -0.12065 -0.305054)
			(stroke
				(width 0.1)
				(type default)
			)
			(layer "F.Fab")
		)
		(fp_line
			(start -0.12065 -0.305054)
			(end -0.12065 -0.2794)
			(stroke
				(width 0.1)
				(type default)
			)
			(layer "F.Fab")
		)
		(pad "1" smd circle
			(at -0.40005 0 270)
			(size 0 0)
			(layers "F.Cu" "F.Mask" "F.Paste")
			(net "P3V3_AUX")
		)
		(pad "2" smd circle
			(at 0.40005 0 270)
			(size 0 0)
			(layers "F.Cu" "F.Mask" "F.Paste")
			(net "HGX_DETECT")
		)
	)
)
